(kicad_pcb
	(version 20260206)
	(generator "pcbnew")
	(generator_version "10.0")
	(general
		(thickness 1.6)
		(legacy_teardrops no)
	)
	(paper "A4")
	(title_block
		(title "Wiwynn_Tioga_Pass_MB.brd")
		(comment 1 "Tioga Pass / footprints 3284-3290 of 4770")
	)
	(layers
		(0 "F.Cu" signal "TOP")
		(4 "In1.Cu" signal "L2GND")
		(6 "In2.Cu" signal "L3")
		(8 "In3.Cu" signal "L4GND")
		(10 "In4.Cu" signal "L5")
		(12 "In5.Cu" signal "L6GND")
		(14 "In6.Cu" signal "L7VCC")
		(16 "In7.Cu" signal "L8VCC")
		(18 "In8.Cu" signal "L9GND")
		(20 "In9.Cu" signal "L10")
		(22 "In10.Cu" signal "L11GND")
		(24 "In11.Cu" signal "L12")
		(26 "In12.Cu" signal "L13GND")
		(2 "B.Cu" signal "BOTTOM")
		(9 "F.Adhes" user "F.Adhesive")
		(11 "B.Adhes" user "B.Adhesive")
		(13 "F.Paste" user "Package Geometry/Pastemask Top")
		(15 "B.Paste" user "Package Geometry/Pastemask Bottom")
		(5 "F.SilkS" user "Ref Des/Silkscreen Top")
		(7 "B.SilkS" user "Ref Des/Silkscreen Bottom")
		(1 "F.Mask" user "Board Geometry/Soldermask Top")
		(3 "B.Mask" user "Board Geometry/Soldermask Bottom")
		(17 "Dwgs.User" user "User.Drawings")
		(19 "Cmts.User" user "User.Comments")
		(21 "Eco1.User" user "User.Eco1")
		(23 "Eco2.User" user "User.Eco2")
		(25 "Edge.Cuts" user "Board Geometry/Outline")
		(27 "Margin" user)
		(31 "F.CrtYd" user "Package Geometry/Place Bound Top")
		(29 "B.CrtYd" user "Package Geometry/Place Bound Bottom")
		(35 "F.Fab" user "Ref Des/Assembly Top")
		(33 "B.Fab" user "Ref Des/Assembly Bottom")
	)
	(footprint ""
		(layer "B.Cu")
		(at 374.4214 -59.9694)
		(property "Reference" "R3P45"
			(at 0 0 0)
			(layer "B.SilkS")
			(hide yes)
			(effects
				(font
					(size 1.27 1.27)
				)
				(justify mirror)
			)
		)
		(property "Value" "*"
			(at -0.064008 -4.108196 0)
			(unlocked yes)
			(layer "B.Fab")
			(hide yes)
			(effects
				(font
					(size 1.27 1.016)
					(thickness 0.1524)
				)
				(justify mirror)
			)
		)
		(property "Device Type" "374R2F-1-GP_SMD-RG-374R2F-1-GPA"
			(at -0.064008 -5.632196 0)
			(unlocked yes)
			(layer "B.Fab")
			(hide yes)
			(effects
				(font
					(size 1.27 1.016)
					(thickness 0.1524)
				)
				(justify mirror)
			)
		)
		(duplicate_pad_numbers_are_jumpers no)
		(fp_line
			(start -0.508 -0.9398)
			(end 0.508 -0.9398)
			(stroke
				(width 0.1524)
				(type default)
			)
			(layer "B.SilkS")
		)
		(fp_line
			(start 0.508 -0.9398)
			(end 0.508 0.9398)
			(stroke
				(width 0.1524)
				(type default)
			)
			(layer "B.SilkS")
		)
		(fp_rect
			(start 0.508 0.9398)
			(end -0.508 -0.9398)
			(stroke
				(width 0)
				(type default)
			)
			(fill no)
			(layer "B.CrtYd")
		)
		(fp_rect
			(start 0.508 0.9398)
			(end -0.508 -0.9398)
			(stroke
				(width 0)
				(type default)
			)
			(fill no)
			(layer "B.Fab")
		)
		(pad "1" smd custom
			(at 0 -0.4445 180)
			(size 0.1397 0.1397)
			(layers "B.Cu" "B.Mask" "B.Paste")
			(net "P3V3")
			(options
				(clearance outline)
				(anchor circle)
			)
			(primitives
				(gr_poly
					(pts
						(arc
							(start -0.1778 0.2794)
							(mid -0.249642 0.249642)
							(end -0.2794 0.1778)
						)
						(arc
							(start -0.2794 -0.1778)
							(mid -0.249642 -0.249642)
							(end -0.1778 -0.2794)
						)
						(arc
							(start 0.1778 -0.2794)
							(mid 0.249642 -0.249642)
							(end 0.2794 -0.1778)
						)
						(arc
							(start 0.2794 0.1778)
							(mid 0.249642 0.249642)
							(end 0.1778 0.2794)
						)
					)
					(width 0)
					(fill yes)
				)
			)
		)
		(pad "2" smd custom
			(at 0 0.4445 180)
			(size 0.1397 0.1397)
			(layers "B.Cu" "B.Mask" "B.Paste")
			(net "P0V7_GTL2104_VREF_1")
			(options
				(clearance outline)
				(anchor circle)
			)
			(primitives
				(gr_poly
					(pts
						(arc
							(start -0.1778 0.2794)
							(mid -0.249642 0.249642)
							(end -0.2794 0.1778)
						)
						(arc
							(start -0.2794 -0.1778)
							(mid -0.249642 -0.249642)
							(end -0.1778 -0.2794)
						)
						(arc
							(start 0.1778 -0.2794)
							(mid 0.249642 -0.249642)
							(end 0.2794 -0.1778)
						)
						(arc
							(start 0.2794 0.1778)
							(mid 0.249642 0.249642)
							(end 0.1778 0.2794)
						)
					)
					(width 0)
					(fill yes)
				)
			)
		)
	)
	(footprint ""
		(layer "B.Cu")
		(at 373.8372 -46.8376 -90)
		(property "Reference" "R2T73"
			(at 0 0 90)
			(layer "B.SilkS")
			(hide yes)
			(effects
				(font
					(size 1.27 1.27)
				)
				(justify mirror)
			)
		)
		(property "Value" ""
			(at 0 0 90)
			(layer "B.Fab")
			(effects
				(font
					(size 1.27 1.27)
				)
				(justify mirror)
			)
		)
		(duplicate_pad_numbers_are_jumpers no)
		(fp_poly
			(pts
				(xy 0.2794 -0.1016) (xy -0.2794 -0.1016) (xy -0.2794 0.9906) (xy 0.2794 0.9906)
			)
			(stroke
				(width 0)
				(type default)
			)
			(fill no)
			(layer "B.CrtYd")
		)
		(fp_line
			(start -0.2794 0.9906)
			(end -0.2794 -0.1016)
			(stroke
				(width 0.1)
				(type default)
			)
			(layer "B.Fab")
		)
		(fp_line
			(start 0.2794 0.9906)
			(end -0.2794 0.9906)
			(stroke
				(width 0.1)
				(type default)
			)
			(layer "B.Fab")
		)
		(fp_line
			(start -0.2794 -0.1016)
			(end 0.2794 -0.1016)
			(stroke
				(width 0.1)
				(type default)
			)
			(layer "B.Fab")
		)
		(fp_line
			(start 0.2794 -0.1016)
			(end 0.2794 0.9906)
			(stroke
				(width 0.1)
				(type default)
			)
			(layer "B.Fab")
		)
		(pad "1" smd rect
			(at 0 0 90)
			(size 0.508 0.508)
			(layers "B.Cu" "B.Mask" "B.Paste")
			(net "PVCCIO_CPU1")
		)
		(pad "2" smd rect
			(at 0 0.889 90)
			(size 0.508 0.508)
			(layers "B.Cu" "B.Mask" "B.Paste")
			(net "H_CPU1_PROCHOT_G_N")
		)
		(zone
			(layer "B.Cu")
			(hatch none 0.5)
			(connect_pads
				(clearance 0)
			)
			(min_thickness 0.25)
			(keepout
				(tracks not_allowed)
				(vias allowed)
				(pads allowed)
				(copperpour not_allowed)
				(footprints allowed)
			)
			(placement
				(enabled no)
				(sheetname "")
			)
			(fill
				(thermal_gap 0.5)
				(thermal_bridge_width 0.5)
				(island_removal_mode 0)
			)
			(polygon
				(pts
					(xy 373.2022 -46.5836) (xy 373.2022 -47.0916) (xy 373.5832 -47.0916) (xy 373.5832 -46.5836)
				)
			)
		)
		(zone
			(layer "B.Cu")
			(hatch none 0.5)
			(connect_pads
				(clearance 0)
			)
			(min_thickness 0.25)
			(keepout
				(tracks allowed)
				(vias not_allowed)
				(pads allowed)
				(copperpour not_allowed)
				(footprints allowed)
			)
			(placement
				(enabled no)
				(sheetname "")
			)
			(fill
				(thermal_gap 0.5)
				(thermal_bridge_width 0.5)
				(island_removal_mode 0)
			)
			(polygon
				(pts
					(xy 373.5832 -46.5836) (xy 373.5832 -47.0916) (xy 373.2022 -47.0916) (xy 373.2022 -46.5836)
				)
			)
		)
	)
	(footprint ""
		(layer "B.Cu")
		(at 365.506 -113.792 -90)
		(property "Reference" "C3M41"
			(at 0 0 90)
			(layer "B.SilkS")
			(hide yes)
			(effects
				(font
					(size 1.27 1.27)
				)
				(justify mirror)
			)
		)
		(property "Value" ""
			(at 0 0 90)
			(layer "B.Fab")
			(effects
				(font
					(size 1.27 1.27)
				)
				(justify mirror)
			)
		)
		(duplicate_pad_numbers_are_jumpers no)
		(fp_poly
			(pts
				(xy -0.3048 -0.1016) (xy -0.3048 0.9906) (xy 0.3048 0.9906) (xy 0.3048 -0.1016)
			)
			(stroke
				(width 0)
				(type default)
			)
			(fill no)
			(layer "B.CrtYd")
		)
		(fp_line
			(start -0.3048 0.9906)
			(end -0.3048 -0.1016)
			(stroke
				(width 0.1)
				(type default)
			)
			(layer "B.Fab")
		)
		(fp_line
			(start 0.3048 0.9906)
			(end -0.3048 0.9906)
			(stroke
				(width 0.1)
				(type default)
			)
			(layer "B.Fab")
		)
		(fp_line
			(start -0.3048 -0.1016)
			(end 0.3048 -0.1016)
			(stroke
				(width 0.1)
				(type default)
			)
			(layer "B.Fab")
		)
		(fp_line
			(start 0.3048 -0.1016)
			(end 0.3048 0.9906)
			(stroke
				(width 0.1)
				(type default)
			)
			(layer "B.Fab")
		)
		(pad "1" smd rect
			(at 0 0 90)
			(size 0.508 0.508)
			(layers "B.Cu" "B.Mask" "B.Paste")
			(net "DMI_CPU0_PCH_RX_DN<1>")
		)
		(pad "2" smd rect
			(at 0 0.889 90)
			(size 0.508 0.508)
			(layers "B.Cu" "B.Mask" "B.Paste")
			(net "DMI_CPU0_PCH_RX_C_DN<1>")
		)
		(zone
			(layer "B.Cu")
			(hatch none 0.5)
			(connect_pads
				(clearance 0)
			)
			(min_thickness 0.25)
			(keepout
				(tracks not_allowed)
				(vias allowed)
				(pads allowed)
				(copperpour not_allowed)
				(footprints allowed)
			)
			(placement
				(enabled no)
				(sheetname "")
			)
			(fill
				(thermal_gap 0.5)
				(thermal_bridge_width 0.5)
				(island_removal_mode 0)
			)
			(polygon
				(pts
					(xy 364.871 -113.538) (xy 364.871 -114.046) (xy 365.252 -114.046) (xy 365.252 -113.538)
				)
			)
		)
		(zone
			(layer "B.Cu")
			(hatch none 0.5)
			(connect_pads
				(clearance 0)
			)
			(min_thickness 0.25)
			(keepout
				(tracks allowed)
				(vias not_allowed)
				(pads allowed)
				(copperpour not_allowed)
				(footprints allowed)
			)
			(placement
				(enabled no)
				(sheetname "")
			)
			(fill
				(thermal_gap 0.5)
				(thermal_bridge_width 0.5)
				(island_removal_mode 0)
			)
			(polygon
				(pts
					(xy 365.252 -113.538) (xy 365.252 -114.046) (xy 364.871 -114.046) (xy 364.871 -113.538)
				)
			)
		)
	)
	(footprint ""
		(layer "B.Cu")
		(at 456.692 -116.49202)
		(property "Reference" "C1M12"
			(at 0 0 0)
			(layer "B.SilkS")
			(hide yes)
			(effects
				(font
					(size 1.27 1.27)
				)
				(justify mirror)
			)
		)
		(property "Value" ""
			(at 0 0 0)
			(layer "B.Fab")
			(effects
				(font
					(size 1.27 1.27)
				)
				(justify mirror)
			)
		)
		(duplicate_pad_numbers_are_jumpers no)
		(fp_rect
			(start -0.3048 0.9906)
			(end 0.3048 -0.1016)
			(stroke
				(width 0)
				(type default)
			)
			(fill no)
			(layer "B.CrtYd")
		)
		(fp_line
			(start -0.3048 -0.1016)
			(end 0.3048 -0.1016)
			(stroke
				(width 0.1)
				(type default)
			)
			(layer "B.Fab")
		)
		(fp_line
			(start -0.3048 0.9906)
			(end -0.3048 -0.1016)
			(stroke
				(width 0.1)
				(type default)
			)
			(layer "B.Fab")
		)
		(fp_line
			(start 0.3048 -0.1016)
			(end 0.3048 0.9906)
			(stroke
				(width 0.1)
				(type default)
			)
			(layer "B.Fab")
		)
		(fp_line
			(start 0.3048 0.9906)
			(end -0.3048 0.9906)
			(stroke
				(width 0.1)
				(type default)
			)
			(layer "B.Fab")
		)
		(pad "1" smd rect
			(at 0 0 180)
			(size 0.508 0.508)
			(layers "B.Cu" "B.Mask" "B.Paste")
			(net "P3E_CPU0_PE3_OCP_TXP<12>")
		)
		(pad "2" smd rect
			(at 0 0.889 180)
			(size 0.508 0.508)
			(layers "B.Cu" "B.Mask" "B.Paste")
			(net "P3E_OCP_CPU0_PE3_C_TXP<12>")
		)
		(zone
			(layer "B.Cu")
			(hatch none 0.5)
			(connect_pads
				(clearance 0)
			)
			(min_thickness 0.25)
			(keepout
				(tracks not_allowed)
				(vias allowed)
				(pads allowed)
				(copperpour not_allowed)
				(footprints allowed)
			)
			(placement
				(enabled no)
				(sheetname "")
			)
			(fill
				(thermal_gap 0.5)
				(thermal_bridge_width 0.5)
				(island_removal_mode 0)
			)
			(polygon
				(pts
					(xy 456.438 -115.85702) (xy 456.946 -115.85702) (xy 456.946 -116.23802) (xy 456.438 -116.23802)
				)
			)
		)
		(zone
			(layer "B.Cu")
			(hatch none 0.5)
			(connect_pads
				(clearance 0)
			)
			(min_thickness 0.25)
			(keepout
				(tracks allowed)
				(vias not_allowed)
				(pads allowed)
				(copperpour not_allowed)
				(footprints allowed)
			)
			(placement
				(enabled no)
				(sheetname "")
			)
			(fill
				(thermal_gap 0.5)
				(thermal_bridge_width 0.5)
				(island_removal_mode 0)
			)
			(polygon
				(pts
					(xy 456.438 -115.85702) (xy 456.946 -115.85702) (xy 456.946 -116.23802) (xy 456.438 -116.23802)
				)
			)
		)
	)
	(footprint ""
		(layer "B.Cu")
		(at 176.25568 -81.407 -90)
		(property "Reference" "R6P13"
			(at 0 0 90)
			(layer "B.SilkS")
			(hide yes)
			(effects
				(font
					(size 1.27 1.27)
				)
				(justify mirror)
			)
		)
		(property "Value" ""
			(at 0 0 90)
			(layer "B.Fab")
			(effects
				(font
					(size 1.27 1.27)
				)
				(justify mirror)
			)
		)
		(duplicate_pad_numbers_are_jumpers no)
		(fp_poly
			(pts
				(xy 0.2794 -0.1016) (xy -0.2794 -0.1016) (xy -0.2794 0.9906) (xy 0.2794 0.9906)
			)
			(stroke
				(width 0)
				(type default)
			)
			(fill no)
			(layer "B.CrtYd")
		)
		(fp_line
			(start -0.2794 0.9906)
			(end -0.2794 -0.1016)
			(stroke
				(width 0.1)
				(type default)
			)
			(layer "B.Fab")
		)
		(fp_line
			(start 0.2794 0.9906)
			(end -0.2794 0.9906)
			(stroke
				(width 0.1)
				(type default)
			)
			(layer "B.Fab")
		)
		(fp_line
			(start -0.2794 -0.1016)
			(end 0.2794 -0.1016)
			(stroke
				(width 0.1)
				(type default)
			)
			(layer "B.Fab")
		)
		(fp_line
			(start 0.2794 -0.1016)
			(end 0.2794 0.9906)
			(stroke
				(width 0.1)
				(type default)
			)
			(layer "B.Fab")
		)
		(pad "1" smd rect
			(at 0 0 90)
			(size 0.508 0.508)
			(layers "B.Cu" "B.Mask" "B.Paste")
			(net "CLK_100M_CPU0_BCLK2_DP")
		)
		(pad "2" smd rect
			(at 0 0.889 90)
			(size 0.508 0.508)
			(layers "B.Cu" "B.Mask" "B.Paste")
			(net "GND")
		)
		(zone
			(layer "B.Cu")
			(hatch none 0.5)
			(connect_pads
				(clearance 0)
			)
			(min_thickness 0.25)
			(keepout
				(tracks not_allowed)
				(vias allowed)
				(pads allowed)
				(copperpour not_allowed)
				(footprints allowed)
			)
			(placement
				(enabled no)
				(sheetname "")
			)
			(fill
				(thermal_gap 0.5)
				(thermal_bridge_width 0.5)
				(island_removal_mode 0)
			)
			(polygon
				(pts
					(xy 175.62068 -81.153) (xy 175.62068 -81.661) (xy 176.00168 -81.661) (xy 176.00168 -81.153)
				)
			)
		)
		(zone
			(layer "B.Cu")
			(hatch none 0.5)
			(connect_pads
				(clearance 0)
			)
			(min_thickness 0.25)
			(keepout
				(tracks allowed)
				(vias not_allowed)
				(pads allowed)
				(copperpour not_allowed)
				(footprints allowed)
			)
			(placement
				(enabled no)
				(sheetname "")
			)
			(fill
				(thermal_gap 0.5)
				(thermal_bridge_width 0.5)
				(island_removal_mode 0)
			)
			(polygon
				(pts
					(xy 176.00168 -81.153) (xy 176.00168 -81.661) (xy 175.62068 -81.661) (xy 175.62068 -81.153)
				)
			)
		)
	)
	(footprint ""
		(layer "B.Cu")
		(at 184.658 -153.416)
		(property "Reference" "R6L4"
			(at 0 0 0)
			(layer "B.SilkS")
			(hide yes)
			(effects
				(font
					(size 1.27 1.27)
				)
				(justify mirror)
			)
		)
		(property "Value" ""
			(at 0 0 0)
			(layer "B.Fab")
			(effects
				(font
					(size 1.27 1.27)
				)
				(justify mirror)
			)
		)
		(duplicate_pad_numbers_are_jumpers no)
		(fp_rect
			(start 0.2794 -0.1016)
			(end -0.2794 0.9906)
			(stroke
				(width 0)
				(type default)
			)
			(fill no)
			(layer "B.CrtYd")
		)
		(fp_line
			(start -0.2794 -0.1016)
			(end 0.2794 -0.1016)
			(stroke
				(width 0.1)
				(type default)
			)
			(layer "B.Fab")
		)
		(fp_line
			(start -0.2794 0.9906)
			(end -0.2794 -0.1016)
			(stroke
				(width 0.1)
				(type default)
			)
			(layer "B.Fab")
		)
		(fp_line
			(start 0.2794 -0.1016)
			(end 0.2794 0.9906)
			(stroke
				(width 0.1)
				(type default)
			)
			(layer "B.Fab")
		)
		(fp_line
			(start 0.2794 0.9906)
			(end -0.2794 0.9906)
			(stroke
				(width 0.1)
				(type default)
			)
			(layer "B.Fab")
		)
		(pad "1" smd rect
			(at 0 0 180)
			(size 0.508 0.508)
			(layers "B.Cu" "B.Mask" "B.Paste")
			(net "P3V3")
		)
		(pad "2" smd rect
			(at 0 0.889 180)
			(size 0.508 0.508)
			(layers "B.Cu" "B.Mask" "B.Paste")
			(net "FM_PVTT_DEF_EN_R")
		)
		(zone
			(layer "B.Cu")
			(hatch none 0.5)
			(connect_pads
				(clearance 0)
			)
			(min_thickness 0.25)
			(keepout
				(tracks allowed)
				(vias not_allowed)
				(pads allowed)
				(copperpour not_allowed)
				(footprints allowed)
			)
			(placement
				(enabled no)
				(sheetname "")
			)
			(fill
				(thermal_gap 0.5)
				(thermal_bridge_width 0.5)
				(island_removal_mode 0)
			)
			(polygon
				(pts
					(xy 184.912 -153.162) (xy 184.404 -153.162) (xy 184.404 -152.781) (xy 184.912 -152.781)
				)
			)
		)
		(zone
			(layer "B.Cu")
			(hatch none 0.5)
			(connect_pads
				(clearance 0)
			)
			(min_thickness 0.25)
			(keepout
				(tracks not_allowed)
				(vias allowed)
				(pads allowed)
				(copperpour not_allowed)
				(footprints allowed)
			)
			(placement
				(enabled no)
				(sheetname "")
			)
			(fill
				(thermal_gap 0.5)
				(thermal_bridge_width 0.5)
				(island_removal_mode 0)
			)
			(polygon
				(pts
					(xy 184.912 -153.162) (xy 184.404 -153.162) (xy 184.404 -152.781) (xy 184.912 -152.781)
				)
			)
		)
	)
	(footprint ""
		(layer "B.Cu")
		(at 371.983 -6.1595)
		(property "Reference" "R7G26"
			(at 0 0 0)
			(layer "B.SilkS")
			(hide yes)
			(effects
				(font
					(size 1.27 1.27)
				)
				(justify mirror)
			)
		)
		(property "Value" ""
			(at 0 0 0)
			(layer "B.Fab")
			(effects
				(font
					(size 1.27 1.27)
				)
				(justify mirror)
			)
		)
		(duplicate_pad_numbers_are_jumpers no)
		(fp_poly
			(pts
				(xy 0.2794 -0.1016) (xy -0.2794 -0.1016) (xy -0.2794 0.9906) (xy 0.2794 0.9906)
			)
			(stroke
				(width 0)
				(type default)
			)
			(fill no)
			(layer "B.CrtYd")
		)
		(fp_line
			(start -0.2794 -0.1016)
			(end 0.2794 -0.1016)
			(stroke
				(width 0.1)
				(type default)
			)
			(layer "B.Fab")
		)
		(fp_line
			(start -0.2794 0.9906)
			(end -0.2794 -0.1016)
			(stroke
				(width 0.1)
				(type default)
			)
			(layer "B.Fab")
		)
		(fp_line
			(start 0.2794 -0.1016)
			(end 0.2794 0.9906)
			(stroke
				(width 0.1)
				(type default)
			)
			(layer "B.Fab")
		)
		(fp_line
			(start 0.2794 0.9906)
			(end -0.2794 0.9906)
			(stroke
				(width 0.1)
				(type default)
			)
			(layer "B.Fab")
		)
		(pad "1" smd rect
			(at 0 0 180)
			(size 0.508 0.508)
			(layers "B.Cu" "B.Mask" "B.Paste")
			(net "P3V3_STBY")
		)
		(pad "2" smd rect
			(at 0 0.889 180)
			(size 0.508 0.508)
			(layers "B.Cu" "B.Mask" "B.Paste")
			(net "FM_ME_RECOVER_N")
		)
		(zone
			(layer "B.Cu")
			(hatch none 0.5)
			(connect_pads
				(clearance 0)
			)
			(min_thickness 0.25)
			(keepout
				(tracks allowed)
				(vias not_allowed)
				(pads allowed)
				(copperpour not_allowed)
				(footprints allowed)
			)
			(placement
				(enabled no)
				(sheetname "")
			)
			(fill
				(thermal_gap 0.5)
				(thermal_bridge_width 0.5)
				(island_removal_mode 0)
			)
			(polygon
				(pts
					(xy 372.237 -5.9055) (xy 371.729 -5.9055) (xy 371.729 -5.5245) (xy 372.237 -5.5245)
				)
			)
		)
		(zone
			(layer "B.Cu")
			(hatch none 0.5)
			(connect_pads
				(clearance 0)
			)
			(min_thickness 0.25)
			(keepout
				(tracks not_allowed)
				(vias allowed)
				(pads allowed)
				(copperpour not_allowed)
				(footprints allowed)
			)
			(placement
				(enabled no)
				(sheetname "")
			)
			(fill
				(thermal_gap 0.5)
				(thermal_bridge_width 0.5)
				(island_removal_mode 0)
			)
			(polygon
				(pts
					(xy 372.237 -5.5245) (xy 371.729 -5.5245) (xy 371.729 -5.9055) (xy 372.237 -5.9055)
				)
			)
		)
	)
)
